# T6G (Grand Teton) — schematic netlist excerpt (pin names and nets, part order shuffled) for the footprints in the layout excerpt that follows; sources: Cadence DE-HDL packaged netlist, KiCad conversion of 04192023_DAF0TMB3IC0_F0TG_MB_C_brd_V02_OCP.brd

R3633  Q_RES  0.002 1% CHIP  pkg 2512LF  page 237 : A = P3V3_OCP_V3_2 ; B = P3V3_OCP_V3_2_R
PC490  Q_CAP  0.22UF 16V 10% X7R  pkg 0402  page 194 : A = SW_PVDDCR_CPU0_P0_BOOT2_RC ; B = SW_PVDDCR_CPU0_P0_PH2
PC149_2  Q_CAP  0.1UF 25V 10% X7R  pkg 0402  page 205 : A = SW_P12V_AUX_PVDDIO_P0_FLT ; B = GND

(kicad_pcb
	(version 20260206)
	(generator "pcbnew")
	(generator_version "10.0")
	(general
		(thickness 1.6)
		(legacy_teardrops no)
	)
	(paper "A4")
	(title_block
		(title "04192023_DAF0TMB3IC0_F0TG_MB_C_brd_V02_OCP.brd")
		(comment 1 "Grand Teton / footprints 2285-2287 of 8354")
	)
	(layers
		(0 "F.Cu" signal "TOP")
		(4 "In1.Cu" signal "GND")
		(6 "In2.Cu" signal "IN1")
		(8 "In3.Cu" signal "GND1")
		(10 "In4.Cu" signal "IN2")
		(12 "In5.Cu" signal "GND2")
		(14 "In6.Cu" signal "IN3")
		(16 "In7.Cu" signal "GND3")
		(18 "In8.Cu" signal "VCC")
		(20 "In9.Cu" signal "VCC1")
		(22 "In10.Cu" signal "GND4")
		(24 "In11.Cu" signal "IN4")
		(26 "In12.Cu" signal "GND5")
		(28 "In13.Cu" signal "IN5")
		(30 "In14.Cu" signal "GND6")
		(32 "In15.Cu" signal "IN6")
		(34 "In16.Cu" signal "GND7")
		(2 "B.Cu" signal "BOTTOM")
		(9 "F.Adhes" user "F.Adhesive")
		(11 "B.Adhes" user "B.Adhesive")
		(13 "F.Paste" user "Package Geometry/Pastemask Top")
		(15 "B.Paste" user "Package Geometry/Pastemask Bottom")
		(5 "F.SilkS" user "Ref Des/Silkscreen Top")
		(7 "B.SilkS" user "Ref Des/Silkscreen Bottom")
		(1 "F.Mask" user "Board Geometry/Soldermask Top")
		(3 "B.Mask" user "Board Geometry/Soldermask Bottom")
		(17 "Dwgs.User" user "User.Drawings")
		(19 "Cmts.User" user "User.Comments")
		(21 "Eco1.User" user "User.Eco1")
		(23 "Eco2.User" user "User.Eco2")
		(25 "Edge.Cuts" user "Board Geometry/Outline")
		(27 "Margin" user)
		(31 "F.CrtYd" user "Package Geometry/Place Bound Top")
		(29 "B.CrtYd" user "Package Geometry/Place Bound Bottom")
		(35 "F.Fab" user "Ref Des/Assembly Top")
		(33 "B.Fab" user "Ref Des/Assembly Bottom")
	)
	(footprint ""
		(layer "F.Cu")
		(at 370.889276 -178.0921 90)
		(property "Reference" "PC490"
			(at 0 0 90)
			(layer "F.SilkS")
			(hide yes)
			(effects
				(font
					(size 1.27 1.27)
				)
			)
		)
		(property "Value" ""
			(at 0 0 90)
			(layer "F.Fab")
			(effects
				(font
					(size 1.27 1.27)
				)
			)
		)
		(duplicate_pad_numbers_are_jumpers no)
		(fp_line
			(start 0.7874 -0.4064)
			(end 0.7874 0.4064)
			(stroke
				(width 0.1524)
				(type default)
			)
			(layer "F.SilkS")
		)
		(fp_line
			(start -0.7874 -0.4064)
			(end 0.7874 -0.4064)
			(stroke
				(width 0.1524)
				(type default)
			)
			(layer "F.SilkS")
		)
		(fp_line
			(start 0.7874 0.4064)
			(end -0.7874 0.4064)
			(stroke
				(width 0.1524)
				(type default)
			)
			(layer "F.SilkS")
		)
		(fp_line
			(start -0.7874 0.4064)
			(end -0.7874 -0.4064)
			(stroke
				(width 0.1524)
				(type default)
			)
			(layer "F.SilkS")
		)
		(fp_line
			(start -0.12065 -0.305054)
			(end -0.12065 -0.2794)
			(stroke
				(width 0.1)
				(type default)
			)
			(layer "F.Fab")
		)
		(fp_line
			(start -0.67945 -0.305054)
			(end -0.12065 -0.305054)
			(stroke
				(width 0.1)
				(type default)
			)
			(layer "F.Fab")
		)
		(fp_line
			(start 0.67945 -0.3048)
			(end 0.67945 0.3048)
			(stroke
				(width 0.1)
				(type default)
			)
			(layer "F.Fab")
		)
		(fp_line
			(start 0.12065 -0.3048)
			(end 0.67945 -0.3048)
			(stroke
				(width 0.1)
				(type default)
			)
			(layer "F.Fab")
		)
		(fp_line
			(start 0.12065 -0.2794)
			(end 0.12065 -0.3048)
			(stroke
				(width 0.1)
				(type default)
			)
			(layer "F.Fab")
		)
		(fp_line
			(start -0.12065 -0.2794)
			(end 0.12065 -0.2794)
			(stroke
				(width 0.1)
				(type default)
			)
			(layer "F.Fab")
		)
		(fp_line
			(start 0.120396 0.2794)
			(end -0.12065 0.2794)
			(stroke
				(width 0.1)
				(type default)
			)
			(layer "F.Fab")
		)
		(fp_line
			(start -0.12065 0.2794)
			(end -0.12065 0.3048)
			(stroke
				(width 0.1)
				(type default)
			)
			(layer "F.Fab")
		)
		(fp_line
			(start 0.67945 0.3048)
			(end 0.120396 0.3048)
			(stroke
				(width 0.1)
				(type default)
			)
			(layer "F.Fab")
		)
		(fp_line
			(start 0.120396 0.3048)
			(end 0.120396 0.2794)
			(stroke
				(width 0.1)
				(type default)
			)
			(layer "F.Fab")
		)
		(fp_line
			(start -0.12065 0.3048)
			(end -0.67945 0.3048)
			(stroke
				(width 0.1)
				(type default)
			)
			(layer "F.Fab")
		)
		(fp_line
			(start -0.67945 0.3048)
			(end -0.67945 -0.305054)
			(stroke
				(width 0.1)
				(type default)
			)
			(layer "F.Fab")
		)
		(pad "1" smd circle
			(at -0.40005 0 90)
			(size 0 0)
			(layers "F.Cu" "F.Mask" "F.Paste")
			(net "SW_PVDDCR_CPU0_P0_BOOT2_RC")
		)
		(pad "2" smd circle
			(at 0.40005 0 90)
			(size 0 0)
			(layers "F.Cu" "F.Mask" "F.Paste")
			(net "SW_PVDDCR_CPU0_P0_PH2")
		)
	)
	(footprint ""
		(layer "F.Cu")
		(at 83.621626 -58.452004 90)
		(property "Reference" "R3633"
			(at -4.884674 -1.833626 0)
			(unlocked yes)
			(layer "F.SilkS")
			(effects
				(font
					(size 0.7874 0.5842)
					(thickness 0.1524)
				)
				(justify left)
			)
		)
		(property "Value" ""
			(at 0 0 90)
			(layer "F.Fab")
			(effects
				(font
					(size 1.27 1.27)
				)
			)
		)
		(duplicate_pad_numbers_are_jumpers no)
		(fp_line
			(start 3.937508 -1.8796)
			(end -3.937508 -1.8796)
			(stroke
				(width 0.1524)
				(type default)
			)
			(layer "F.SilkS")
		)
		(fp_line
			(start -3.937508 -1.8796)
			(end -3.937508 1.8796)
			(stroke
				(width 0.1524)
				(type default)
			)
			(layer "F.SilkS")
		)
		(fp_line
			(start 3.937508 1.8796)
			(end 3.937508 -1.8796)
			(stroke
				(width 0.1524)
				(type default)
			)
			(layer "F.SilkS")
		)
		(fp_line
			(start -3.937508 1.8796)
			(end 3.937508 1.8796)
			(stroke
				(width 0.1524)
				(type default)
			)
			(layer "F.SilkS")
		)
		(fp_line
			(start 3.275076 -1.674876)
			(end -3.275076 -1.674876)
			(stroke
				(width 0.1)
				(type default)
			)
			(layer "F.Fab")
		)
		(fp_line
			(start -3.275076 -1.674876)
			(end -3.275076 1.674876)
			(stroke
				(width 0.1)
				(type default)
			)
			(layer "F.Fab")
		)
		(fp_line
			(start 3.275076 1.674876)
			(end 3.275076 -1.674876)
			(stroke
				(width 0.1)
				(type default)
			)
			(layer "F.Fab")
		)
		(fp_line
			(start -3.275076 1.674876)
			(end 3.275076 1.674876)
			(stroke
				(width 0.1)
				(type default)
			)
			(layer "F.Fab")
		)
		(pad "1" smd rect
			(at -2.350008 0 90)
			(size 2.921 3.5052)
			(layers "F.Cu" "F.Mask" "F.Paste")
			(net "P3V3_OCP_V3_2")
		)
		(pad "2" smd rect
			(at 2.350008 0 90)
			(size 2.921 3.5052)
			(layers "F.Cu" "F.Mask" "F.Paste")
			(net "P3V3_OCP_V3_2_R")
		)
	)
	(footprint ""
		(layer "F.Cu")
		(at 287.87217 -351.100644)
		(property "Reference" "PC149_2"
			(at 0 0 0)
			(layer "F.SilkS")
			(hide yes)
			(effects
				(font
					(size 1.27 1.27)
				)
			)
		)
		(property "Value" ""
			(at 0 0 0)
			(layer "F.Fab")
			(effects
				(font
					(size 1.27 1.27)
				)
			)
		)
		(duplicate_pad_numbers_are_jumpers no)
		(fp_line
			(start -0.7874 -0.4064)
			(end 0.7874 -0.4064)
			(stroke
				(width 0.1524)
				(type default)
			)
			(layer "F.SilkS")
		)
		(fp_line
			(start -0.7874 0.4064)
			(end -0.7874 -0.4064)
			(stroke
				(width 0.1524)
				(type default)
			)
			(layer "F.SilkS")
		)
		(fp_line
			(start 0.7874 -0.4064)
			(end 0.7874 0.4064)
			(stroke
				(width 0.1524)
				(type default)
			)
			(layer "F.SilkS")
		)
		(fp_line
			(start 0.7874 0.4064)
			(end -0.7874 0.4064)
			(stroke
				(width 0.1524)
				(type default)
			)
			(layer "F.SilkS")
		)
		(fp_line
			(start -0.67945 -0.305054)
			(end -0.12065 -0.305054)
			(stroke
				(width 0.1)
				(type default)
			)
			(layer "F.Fab")
		)
		(fp_line
			(start -0.67945 0.3048)
			(end -0.67945 -0.305054)
			(stroke
				(width 0.1)
				(type default)
			)
			(layer "F.Fab")
		)
		(fp_line
			(start -0.12065 -0.305054)
			(end -0.12065 -0.2794)
			(stroke
				(width 0.1)
				(type default)
			)
			(layer "F.Fab")
		)
		(fp_line
			(start -0.12065 -0.2794)
			(end 0.12065 -0.2794)
			(stroke
				(width 0.1)
				(type default)
			)
			(layer "F.Fab")
		)
		(fp_line
			(start -0.12065 0.2794)
			(end -0.12065 0.3048)
			(stroke
				(width 0.1)
				(type default)
			)
			(layer "F.Fab")
		)
		(fp_line
			(start -0.12065 0.3048)
			(end -0.67945 0.3048)
			(stroke
				(width 0.1)
				(type default)
			)
			(layer "F.Fab")
		)
		(fp_line
			(start 0.120396 0.2794)
			(end -0.12065 0.2794)
			(stroke
				(width 0.1)
				(type default)
			)
			(layer "F.Fab")
		)
		(fp_line
			(start 0.120396 0.3048)
			(end 0.120396 0.2794)
			(stroke
				(width 0.1)
				(type default)
			)
			(layer "F.Fab")
		)
		(fp_line
			(start 0.12065 -0.3048)
			(end 0.67945 -0.3048)
			(stroke
				(width 0.1)
				(type default)
			)
			(layer "F.Fab")
		)
		(fp_line
			(start 0.12065 -0.2794)
			(end 0.12065 -0.3048)
			(stroke
				(width 0.1)
				(type default)
			)
			(layer "F.Fab")
		)
		(fp_line
			(start 0.67945 -0.3048)
			(end 0.67945 0.3048)
			(stroke
				(width 0.1)
				(type default)
			)
			(layer "F.Fab")
		)
		(fp_line
			(start 0.67945 0.3048)
			(end 0.120396 0.3048)
			(stroke
				(width 0.1)
				(type default)
			)
			(layer "F.Fab")
		)
		(pad "1" smd circle
			(at -0.40005 0)
			(size 0 0)
			(layers "F.Cu" "F.Mask" "F.Paste")
			(net "SW_P12V_AUX_PVDDIO_P0_FLT")
		)
		(pad "2" smd circle
			(at 0.40005 0)
			(size 0 0)
			(layers "F.Cu" "F.Mask" "F.Paste")
			(net "GND")
		)
	)
)
